FILE_TYPE = MULTI_PHYS_TABLE;

PART 'NCP698SQ15T1G'

{========================================================================================}
:VALUE           | PART_TYPE | MATERIAL | PART_NUMBER    = STANDARD | LIFECYCLE      | PART_NUMBER   | JEDEC_TYPE             | DESCRIPTION                           | MANUFTR | MANUF_PN        | RD_CMPLS_LVL | CMPLS_LVL | FROM_PJ      | CLASS | DIP_SMD | DATA                    | EE_CHECK_LIST | FP_ECN | PSL | CREATOR | STATUS | MSD  | ESD_CDM | ESD_HBM | ESD_MM | PIN_LENGTH_SHORT_PIN | PIN_LENGTH_LONG_PIN | CREATEDAY  ;
{========================================================================================}
 'NCP698SQ15T1G' | 'SMLF'    | 'IC'     | 'AL000698000'(!) = 'End of Design'  | 'Comp-Approve'   | 'AL000698000' |'SC82-AB-4_1-3_2X1-25'| 'IC OTHER(4P) NCP698SQ15T1G(SC82-AB)' | 'ONS'   | 'NCP698SQ15T1G' | 'EP(V1)'     | 'EP(V1)'  | 'T7A-JOSEPH' | 'IC'  | ''      | 'ONS_NCP698SQ15T1G.pdf' | ''            | ''     | ''  | ''      | ''     | 'NA' | 'NA'    | 'NA'    | 'NA'   | '0 MILS'             | '0 MILS'            | '20160920'
 'NCP698SQ15T1G' | 'SMLF'    | 'EMPTY'  | 'AL000698000'(!) = 'End of Design'  | 'Comp-Approve'   | 'AL000698000' |'SC82-AB-4_1-3_2X1-25'| 'IC OTHER(4P) NCP698SQ15T1G(SC82-AB)' | 'ONS'   | 'NCP698SQ15T1G' | 'EP(V1)'     | 'EP(V1)'  | 'T7A-JOSEPH' | 'IC'  | ''      | 'ONS_NCP698SQ15T1G.pdf' | ''            | ''     | ''  | ''      | ''     | 'NA' | 'NA'    | 'NA'    | 'NA'   | '0 MILS'             | '0 MILS'            | '20160920'

END_PART

END.

